(kicad_pcb
	(version 20260206)
	(generator "pcbnew")
	(generator_version "10.0")
	(general
		(thickness 1.6)
		(legacy_teardrops no)
	)
	(paper "A4")
	(title_block
		(title "01162023_DA0F0TEBIF0_F0T_Expander_BD_F_brd_V02_OCP.brd")
		(comment 1 "Grand Teton / footprints 1200-1204 of 9728")
	)
	(layers
		(0 "F.Cu" signal "TOP")
		(4 "In1.Cu" signal "GND")
		(6 "In2.Cu" signal "VCC")
		(8 "In3.Cu" signal "VCC1")
		(10 "In4.Cu" signal "GND1")
		(12 "In5.Cu" signal "IN1")
		(14 "In6.Cu" signal "GND2")
		(16 "In7.Cu" signal "IN2")
		(18 "In8.Cu" signal "GND3")
		(20 "In9.Cu" signal "IN3")
		(22 "In10.Cu" signal "GND4")
		(24 "In11.Cu" signal "IN4")
		(26 "In12.Cu" signal "GND5")
		(28 "In13.Cu" signal "IN5")
		(30 "In14.Cu" signal "GND6")
		(32 "In15.Cu" signal "IN6")
		(34 "In16.Cu" signal "GND7")
		(2 "B.Cu" signal "BOTTOM")
		(9 "F.Adhes" user "F.Adhesive")
		(11 "B.Adhes" user "B.Adhesive")
		(13 "F.Paste" user "Package Geometry/Pastemask Top")
		(15 "B.Paste" user "Package Geometry/Pastemask Bottom")
		(5 "F.SilkS" user "Ref Des/Silkscreen Top")
		(7 "B.SilkS" user "Ref Des/Silkscreen Bottom")
		(1 "F.Mask" user "Board Geometry/Soldermask Top")
		(3 "B.Mask" user "Board Geometry/Soldermask Bottom")
		(17 "Dwgs.User" user "User.Drawings")
		(19 "Cmts.User" user "User.Comments")
		(21 "Eco1.User" user "User.Eco1")
		(23 "Eco2.User" user "User.Eco2")
		(25 "Edge.Cuts" user "Board Geometry/Outline")
		(27 "Margin" user)
		(31 "F.CrtYd" user "Package Geometry/Place Bound Top")
		(29 "B.CrtYd" user "Package Geometry/Place Bound Bottom")
		(35 "F.Fab" user "Ref Des/Assembly Top")
		(33 "B.Fab" user "Ref Des/Assembly Bottom")
	)
	(footprint ""
		(layer "F.Cu")
		(at 346.075 -146.177)
		(property "Reference" "U350"
			(at -1.4478 -4.613148 0)
			(unlocked yes)
			(layer "F.SilkS")
			(effects
				(font
					(size 0.7874 0.5842)
					(thickness 0.1524)
				)
				(justify left)
			)
		)
		(property "Value" ""
			(at 0 0 0)
			(layer "F.Fab")
			(effects
				(font
					(size 1.27 1.27)
				)
			)
		)
		(duplicate_pad_numbers_are_jumpers no)
		(fp_line
			(start -2.097532 -3.949954)
			(end -2.097532 3.949954)
			(stroke
				(width 0.1524)
				(type default)
			)
			(layer "F.SilkS")
		)
		(fp_line
			(start -2.097532 3.949954)
			(end 2.097532 3.949954)
			(stroke
				(width 0.1524)
				(type default)
			)
			(layer "F.SilkS")
		)
		(fp_line
			(start -1.409954 -3.949954)
			(end -2.097532 -3.949954)
			(stroke
				(width 0.1524)
				(type default)
			)
			(layer "F.SilkS")
		)
		(fp_line
			(start 0 -2.54)
			(end -1.409954 -3.949954)
			(stroke
				(width 0.1524)
				(type default)
			)
			(layer "F.SilkS")
		)
		(fp_line
			(start 1.409954 -3.949954)
			(end 0 -2.54)
			(stroke
				(width 0.1524)
				(type default)
			)
			(layer "F.SilkS")
		)
		(fp_line
			(start 2.097532 -3.949954)
			(end 1.409954 -3.949954)
			(stroke
				(width 0.1524)
				(type default)
			)
			(layer "F.SilkS")
		)
		(fp_line
			(start 2.097532 3.949954)
			(end 2.097532 -3.949954)
			(stroke
				(width 0.1524)
				(type default)
			)
			(layer "F.SilkS")
		)
		(fp_poly
			(pts
				(xy -4.7498 -4.182872) (xy -4.7498 -3.166872) (xy -3.7338 -3.674872)
			)
			(stroke
				(width 0)
				(type default)
			)
			(fill yes)
			(layer "F.SilkS")
		)
		(fp_line
			(start -2.249932 -3.949954)
			(end -2.249932 3.949954)
			(stroke
				(width 0.1)
				(type default)
			)
			(layer "F.Fab")
		)
		(fp_line
			(start -2.249932 3.949954)
			(end 2.249932 3.949954)
			(stroke
				(width 0.1)
				(type default)
			)
			(layer "F.Fab")
		)
		(fp_line
			(start 2.249932 -3.949954)
			(end -2.249932 -3.949954)
			(stroke
				(width 0.1)
				(type default)
			)
			(layer "F.Fab")
		)
		(fp_line
			(start 2.249932 3.949954)
			(end 2.249932 -3.949954)
			(stroke
				(width 0.1)
				(type default)
			)
			(layer "F.Fab")
		)
		(fp_poly
			(pts
				(xy -4.7498 -4.182872) (xy -4.7498 -3.166872) (xy -3.7338 -3.674872)
			)
			(stroke
				(width 0)
				(type default)
			)
			(fill yes)
			(layer "F.Fab")
		)
		(pad "1" smd rect
			(at -2.925064 -3.674872 270)
			(size 0.6096 1.3716)
			(layers "F.Cu" "F.Mask" "F.Paste")
			(net "PEX3_PCA9555_1_INT_N")
		)
		(pad "2" smd rect
			(at -2.925064 -2.925064 270)
			(size 0.4064 1.3716)
			(layers "F.Cu" "F.Mask" "F.Paste")
			(net "PCA9555_1_PEX3_A1")
		)
		(pad "3" smd rect
			(at -2.925064 -2.275078 270)
			(size 0.4064 1.3716)
			(layers "F.Cu" "F.Mask" "F.Paste")
			(net "PCA9555_1_PEX3_A2")
		)
		(pad "4" smd rect
			(at -2.925064 -1.625092 270)
			(size 0.4064 1.3716)
			(layers "F.Cu" "F.Mask" "F.Paste")
			(net "PRSNT_SSD14_FPGA_PCA9555_N")
		)
		(pad "5" smd rect
			(at -2.925064 -0.975106 270)
			(size 0.4064 1.3716)
			(layers "F.Cu" "F.Mask" "F.Paste")
			(net "SSD14_PEX_PWR_EN")
		)
		(pad "6" smd rect
			(at -2.925064 -0.32512 270)
			(size 0.4064 1.3716)
			(layers "F.Cu" "F.Mask" "F.Paste")
			(net "RST_PEX_SSD14_PERST_N")
		)
		(pad "7" smd rect
			(at -2.925064 0.32512 270)
			(size 0.4064 1.3716)
			(layers "F.Cu" "F.Mask" "F.Paste")
			(net "Net_1191")
		)
		(pad "8" smd rect
			(at -2.925064 0.975106 270)
			(size 0.4064 1.3716)
			(layers "F.Cu" "F.Mask" "F.Paste")
			(net "PRSNT_SSD15_FPGA_PCA9555_N")
		)
		(pad "9" smd rect
			(at -2.925064 1.625092 270)
			(size 0.4064 1.3716)
			(layers "F.Cu" "F.Mask" "F.Paste")
			(net "SSD15_PEX_PWR_EN")
		)
		(pad "10" smd rect
			(at -2.925064 2.275078 270)
			(size 0.4064 1.3716)
			(layers "F.Cu" "F.Mask" "F.Paste")
			(net "RST_PEX_SSD15_PERST_N")
		)
		(pad "11" smd rect
			(at -2.925064 2.925064 270)
			(size 0.4064 1.3716)
			(layers "F.Cu" "F.Mask" "F.Paste")
			(net "Net_1189")
		)
		(pad "12" smd rect
			(at -2.925064 3.674872 270)
			(size 0.6096 1.3716)
			(layers "F.Cu" "F.Mask" "F.Paste")
			(net "GND")
		)
		(pad "13" smd rect
			(at 2.925064 3.674872 270)
			(size 0.6096 1.3716)
			(layers "F.Cu" "F.Mask" "F.Paste")
			(net "PRSNT_NIC7_FPGA_PCA9555_N")
		)
		(pad "14" smd rect
			(at 2.925064 2.925064 270)
			(size 0.4064 1.3716)
			(layers "F.Cu" "F.Mask" "F.Paste")
			(net "NIC7_PEX_PWR_EN")
		)
		(pad "15" smd rect
			(at 2.925064 2.275078 270)
			(size 0.4064 1.3716)
			(layers "F.Cu" "F.Mask" "F.Paste")
			(net "RST_PEX_NIC7_PERST_N")
		)
		(pad "16" smd rect
			(at 2.925064 1.625092 270)
			(size 0.4064 1.3716)
			(layers "F.Cu" "F.Mask" "F.Paste")
			(net "Net_1190")
		)
		(pad "17" smd rect
			(at 2.925064 0.975106 270)
			(size 0.4064 1.3716)
			(layers "F.Cu" "F.Mask" "F.Paste")
			(net "Net_8964")
		)
		(pad "18" smd rect
			(at 2.925064 0.32512 270)
			(size 0.4064 1.3716)
			(layers "F.Cu" "F.Mask" "F.Paste")
			(net "Net_8963")
		)
		(pad "19" smd rect
			(at 2.925064 -0.32512 270)
			(size 0.4064 1.3716)
			(layers "F.Cu" "F.Mask" "F.Paste")
			(net "Net_8962")
		)
		(pad "20" smd rect
			(at 2.925064 -0.975106 270)
			(size 0.4064 1.3716)
			(layers "F.Cu" "F.Mask" "F.Paste")
			(net "Net_8961")
		)
		(pad "21" smd rect
			(at 2.925064 -1.625092 270)
			(size 0.4064 1.3716)
			(layers "F.Cu" "F.Mask" "F.Paste")
			(net "PCA9555_1_PEX3_A0")
		)
		(pad "22" smd rect
			(at 2.925064 -2.275078 270)
			(size 0.4064 1.3716)
			(layers "F.Cu" "F.Mask" "F.Paste")
			(net "SMB_PEX3_PCA9555_SCL")
		)
		(pad "23" smd rect
			(at 2.925064 -2.925064 270)
			(size 0.4064 1.3716)
			(layers "F.Cu" "F.Mask" "F.Paste")
			(net "SMB_PEX3_PCA9555_SDA")
		)
		(pad "24" smd rect
			(at 2.925064 -3.674872 270)
			(size 0.6096 1.3716)
			(layers "F.Cu" "F.Mask" "F.Paste")
			(net "P3V3_AUX")
		)
	)
	(footprint ""
		(layer "F.Cu")
		(at 160.73882 -22.867366 90)
		(property "Reference" "C3910"
			(at 0 0 90)
			(layer "F.SilkS")
			(hide yes)
			(effects
				(font
					(size 1.27 1.27)
				)
			)
		)
		(property "Value" ""
			(at 0 0 90)
			(layer "F.Fab")
			(effects
				(font
					(size 1.27 1.27)
				)
			)
		)
		(duplicate_pad_numbers_are_jumpers no)
		(fp_line
			(start 0.7874 -0.4064)
			(end 0.7874 0.4064)
			(stroke
				(width 0.1524)
				(type default)
			)
			(layer "F.SilkS")
		)
		(fp_line
			(start -0.7874 -0.4064)
			(end 0.7874 -0.4064)
			(stroke
				(width 0.1524)
				(type default)
			)
			(layer "F.SilkS")
		)
		(fp_line
			(start 0.7874 0.4064)
			(end -0.7874 0.4064)
			(stroke
				(width 0.1524)
				(type default)
			)
			(layer "F.SilkS")
		)
		(fp_line
			(start -0.7874 0.4064)
			(end -0.7874 -0.4064)
			(stroke
				(width 0.1524)
				(type default)
			)
			(layer "F.SilkS")
		)
		(fp_line
			(start -0.12065 -0.305054)
			(end -0.12065 -0.2794)
			(stroke
				(width 0.1)
				(type default)
			)
			(layer "F.Fab")
		)
		(fp_line
			(start -0.67945 -0.305054)
			(end -0.12065 -0.305054)
			(stroke
				(width 0.1)
				(type default)
			)
			(layer "F.Fab")
		)
		(fp_line
			(start 0.67945 -0.3048)
			(end 0.67945 0.3048)
			(stroke
				(width 0.1)
				(type default)
			)
			(layer "F.Fab")
		)
		(fp_line
			(start 0.12065 -0.3048)
			(end 0.67945 -0.3048)
			(stroke
				(width 0.1)
				(type default)
			)
			(layer "F.Fab")
		)
		(fp_line
			(start 0.12065 -0.2794)
			(end 0.12065 -0.3048)
			(stroke
				(width 0.1)
				(type default)
			)
			(layer "F.Fab")
		)
		(fp_line
			(start -0.12065 -0.2794)
			(end 0.12065 -0.2794)
			(stroke
				(width 0.1)
				(type default)
			)
			(layer "F.Fab")
		)
		(fp_line
			(start 0.120396 0.2794)
			(end -0.12065 0.2794)
			(stroke
				(width 0.1)
				(type default)
			)
			(layer "F.Fab")
		)
		(fp_line
			(start -0.12065 0.2794)
			(end -0.12065 0.3048)
			(stroke
				(width 0.1)
				(type default)
			)
			(layer "F.Fab")
		)
		(fp_line
			(start 0.67945 0.3048)
			(end 0.120396 0.3048)
			(stroke
				(width 0.1)
				(type default)
			)
			(layer "F.Fab")
		)
		(fp_line
			(start 0.120396 0.3048)
			(end 0.120396 0.2794)
			(stroke
				(width 0.1)
				(type default)
			)
			(layer "F.Fab")
		)
		(fp_line
			(start -0.12065 0.3048)
			(end -0.67945 0.3048)
			(stroke
				(width 0.1)
				(type default)
			)
			(layer "F.Fab")
		)
		(fp_line
			(start -0.67945 0.3048)
			(end -0.67945 -0.305054)
			(stroke
				(width 0.1)
				(type default)
			)
			(layer "F.Fab")
		)
		(pad "1" smd circle
			(at -0.40005 0 90)
			(size 0 0)
			(layers "F.Cu" "F.Mask" "F.Paste")
			(net "P12V_SSD5")
		)
		(pad "2" smd circle
			(at 0.40005 0 90)
			(size 0 0)
			(layers "F.Cu" "F.Mask" "F.Paste")
			(net "GND")
		)
	)
	(footprint ""
		(layer "F.Cu")
		(at 38.608 -153.3144 180)
		(property "Reference" "R25"
			(at 0 0 180)
			(layer "F.SilkS")
			(hide yes)
			(effects
				(font
					(size 1.27 1.27)
				)
			)
		)
		(property "Value" ""
			(at 0 0 180)
			(layer "F.Fab")
			(effects
				(font
					(size 1.27 1.27)
				)
			)
		)
		(duplicate_pad_numbers_are_jumpers no)
		(fp_line
			(start 0.7874 0.4064)
			(end -0.7874 0.4064)
			(stroke
				(width 0.1524)
				(type default)
			)
			(layer "F.SilkS")
		)
		(fp_line
			(start 0.7874 -0.4064)
			(end 0.7874 0.4064)
			(stroke
				(width 0.1524)
				(type default)
			)
			(layer "F.SilkS")
		)
		(fp_line
			(start -0.7874 0.4064)
			(end -0.7874 -0.4064)
			(stroke
				(width 0.1524)
				(type default)
			)
			(layer "F.SilkS")
		)
		(fp_line
			(start -0.7874 -0.4064)
			(end 0.7874 -0.4064)
			(stroke
				(width 0.1524)
				(type default)
			)
			(layer "F.SilkS")
		)
		(fp_line
			(start 0.67945 0.3048)
			(end 0.120396 0.3048)
			(stroke
				(width 0.1)
				(type default)
			)
			(layer "F.Fab")
		)
		(fp_line
			(start 0.67945 -0.3048)
			(end 0.67945 0.3048)
			(stroke
				(width 0.1)
				(type default)
			)
			(layer "F.Fab")
		)
		(fp_line
			(start 0.12065 -0.2794)
			(end 0.12065 -0.3048)
			(stroke
				(width 0.1)
				(type default)
			)
			(layer "F.Fab")
		)
		(fp_line
			(start 0.12065 -0.3048)
			(end 0.67945 -0.3048)
			(stroke
				(width 0.1)
				(type default)
			)
			(layer "F.Fab")
		)
		(fp_line
			(start 0.120396 0.3048)
			(end 0.120396 0.2794)
			(stroke
				(width 0.1)
				(type default)
			)
			(layer "F.Fab")
		)
		(fp_line
			(start 0.120396 0.2794)
			(end -0.12065 0.2794)
			(stroke
				(width 0.1)
				(type default)
			)
			(layer "F.Fab")
		)
		(fp_line
			(start -0.12065 0.3048)
			(end -0.67945 0.3048)
			(stroke
				(width 0.1)
				(type default)
			)
			(layer "F.Fab")
		)
		(fp_line
			(start -0.12065 0.2794)
			(end -0.12065 0.3048)
			(stroke
				(width 0.1)
				(type default)
			)
			(layer "F.Fab")
		)
		(fp_line
			(start -0.12065 -0.2794)
			(end 0.12065 -0.2794)
			(stroke
				(width 0.1)
				(type default)
			)
			(layer "F.Fab")
		)
		(fp_line
			(start -0.12065 -0.305054)
			(end -0.12065 -0.2794)
			(stroke
				(width 0.1)
				(type default)
			)
			(layer "F.Fab")
		)
		(fp_line
			(start -0.67945 0.3048)
			(end -0.67945 -0.305054)
			(stroke
				(width 0.1)
				(type default)
			)
			(layer "F.Fab")
		)
		(fp_line
			(start -0.67945 -0.305054)
			(end -0.12065 -0.305054)
			(stroke
				(width 0.1)
				(type default)
			)
			(layer "F.Fab")
		)
		(pad "1" smd circle
			(at -0.40005 0 180)
			(size 0 0)
			(layers "F.Cu" "F.Mask" "F.Paste")
			(net "NIC0_SLOT_ID0")
		)
		(pad "2" smd circle
			(at 0.40005 0 180)
			(size 0 0)
			(layers "F.Cu" "F.Mask" "F.Paste")
			(net "P3V3_NIC0")
		)
	)
	(footprint ""
		(layer "F.Cu")
		(at 33.287716 -298.020232)
		(property "Reference" "C3021"
			(at 0 0 0)
			(layer "F.SilkS")
			(hide yes)
			(effects
				(font
					(size 1.27 1.27)
				)
			)
		)
		(property "Value" ""
			(at 0 0 0)
			(layer "F.Fab")
			(effects
				(font
					(size 1.27 1.27)
				)
			)
		)
		(duplicate_pad_numbers_are_jumpers no)
		(fp_line
			(start -1.2954 -0.5842)
			(end 1.2954 -0.5842)
			(stroke
				(width 0.1524)
				(type default)
			)
			(layer "F.SilkS")
		)
		(fp_line
			(start -1.2954 0.5842)
			(end -1.2954 -0.5842)
			(stroke
				(width 0.1524)
				(type default)
			)
			(layer "F.SilkS")
		)
		(fp_line
			(start 1.2954 -0.5842)
			(end 1.2954 0.5842)
			(stroke
				(width 0.1524)
				(type default)
			)
			(layer "F.SilkS")
		)
		(fp_line
			(start 1.2954 0.5842)
			(end -1.2954 0.5842)
			(stroke
				(width 0.1524)
				(type default)
			)
			(layer "F.SilkS")
		)
		(fp_line
			(start -1.1938 -0.4064)
			(end -0.8636 -0.4064)
			(stroke
				(width 0.1)
				(type default)
			)
			(layer "F.Fab")
		)
		(fp_line
			(start -1.1938 0.4064)
			(end -1.1938 -0.4064)
			(stroke
				(width 0.1)
				(type default)
			)
			(layer "F.Fab")
		)
		(fp_line
			(start -0.8636 -0.4572)
			(end 0.8636 -0.4572)
			(stroke
				(width 0.1)
				(type default)
			)
			(layer "F.Fab")
		)
		(fp_line
			(start -0.8636 -0.4064)
			(end -0.8636 -0.4572)
			(stroke
				(width 0.1)
				(type default)
			)
			(layer "F.Fab")
		)
		(fp_line
			(start -0.8636 0.4064)
			(end -1.1938 0.4064)
			(stroke
				(width 0.1)
				(type default)
			)
			(layer "F.Fab")
		)
		(fp_line
			(start -0.8636 0.4572)
			(end -0.8636 0.4064)
			(stroke
				(width 0.1)
				(type default)
			)
			(layer "F.Fab")
		)
		(fp_line
			(start 0.8636 -0.4572)
			(end 0.8636 -0.4064)
			(stroke
				(width 0.1)
				(type default)
			)
			(layer "F.Fab")
		)
		(fp_line
			(start 0.8636 -0.4064)
			(end 1.1938 -0.4064)
			(stroke
				(width 0.1)
				(type default)
			)
			(layer "F.Fab")
		)
		(fp_line
			(start 0.8636 0.4064)
			(end 0.8636 0.4572)
			(stroke
				(width 0.1)
				(type default)
			)
			(layer "F.Fab")
		)
		(fp_line
			(start 0.8636 0.4572)
			(end -0.8636 0.4572)
			(stroke
				(width 0.1)
				(type default)
			)
			(layer "F.Fab")
		)
		(fp_line
			(start 1.1938 -0.4064)
			(end 1.1938 0.4064)
			(stroke
				(width 0.1)
				(type default)
			)
			(layer "F.Fab")
		)
		(fp_line
			(start 1.1938 0.4064)
			(end 0.8636 0.4064)
			(stroke
				(width 0.1)
				(type default)
			)
			(layer "F.Fab")
		)
		(pad "1" smd rect
			(at -0.7366 0 270)
			(size 0.7112 0.8128)
			(layers "F.Cu" "F.Mask" "F.Paste")
			(net "PCEPLL0_VDDA18_PEX0")
		)
		(pad "2" smd rect
			(at 0.7366 0 270)
			(size 0.7112 0.8128)
			(layers "F.Cu" "F.Mask" "F.Paste")
			(net "GND")
		)
	)
	(footprint ""
		(layer "F.Cu")
		(at 239.460278 -65.072006 -90)
		(property "Reference" "R5996"
			(at 0 0 270)
			(layer "F.SilkS")
			(hide yes)
			(effects
				(font
					(size 1.27 1.27)
				)
			)
		)
		(property "Value" ""
			(at 0 0 270)
			(layer "F.Fab")
			(effects
				(font
					(size 1.27 1.27)
				)
			)
		)
		(duplicate_pad_numbers_are_jumpers no)
		(fp_line
			(start -0.7874 0.4064)
			(end -0.7874 -0.4064)
			(stroke
				(width 0.1524)
				(type default)
			)
			(layer "F.SilkS")
		)
		(fp_line
			(start 0.7874 0.4064)
			(end -0.7874 0.4064)
			(stroke
				(width 0.1524)
				(type default)
			)
			(layer "F.SilkS")
		)
		(fp_line
			(start -0.7874 -0.4064)
			(end 0.7874 -0.4064)
			(stroke
				(width 0.1524)
				(type default)
			)
			(layer "F.SilkS")
		)
		(fp_line
			(start 0.7874 -0.4064)
			(end 0.7874 0.4064)
			(stroke
				(width 0.1524)
				(type default)
			)
			(layer "F.SilkS")
		)
		(fp_line
			(start -0.67945 0.3048)
			(end -0.67945 -0.305054)
			(stroke
				(width 0.1)
				(type default)
			)
			(layer "F.Fab")
		)
		(fp_line
			(start -0.12065 0.3048)
			(end -0.67945 0.3048)
			(stroke
				(width 0.1)
				(type default)
			)
			(layer "F.Fab")
		)
		(fp_line
			(start 0.120396 0.3048)
			(end 0.120396 0.2794)
			(stroke
				(width 0.1)
				(type default)
			)
			(layer "F.Fab")
		)
		(fp_line
			(start 0.67945 0.3048)
			(end 0.120396 0.3048)
			(stroke
				(width 0.1)
				(type default)
			)
			(layer "F.Fab")
		)
		(fp_line
			(start -0.12065 0.2794)
			(end -0.12065 0.3048)
			(stroke
				(width 0.1)
				(type default)
			)
			(layer "F.Fab")
		)
		(fp_line
			(start 0.120396 0.2794)
			(end -0.12065 0.2794)
			(stroke
				(width 0.1)
				(type default)
			)
			(layer "F.Fab")
		)
		(fp_line
			(start -0.12065 -0.2794)
			(end 0.12065 -0.2794)
			(stroke
				(width 0.1)
				(type default)
			)
			(layer "F.Fab")
		)
		(fp_line
			(start 0.12065 -0.2794)
			(end 0.12065 -0.3048)
			(stroke
				(width 0.1)
				(type default)
			)
			(layer "F.Fab")
		)
		(fp_line
			(start 0.12065 -0.3048)
			(end 0.67945 -0.3048)
			(stroke
				(width 0.1)
				(type default)
			)
			(layer "F.Fab")
		)
		(fp_line
			(start 0.67945 -0.3048)
			(end 0.67945 0.3048)
			(stroke
				(width 0.1)
				(type default)
			)
			(layer "F.Fab")
		)
		(fp_line
			(start -0.67945 -0.305054)
			(end -0.12065 -0.305054)
			(stroke
				(width 0.1)
				(type default)
			)
			(layer "F.Fab")
		)
		(fp_line
			(start -0.12065 -0.305054)
			(end -0.12065 -0.2794)
			(stroke
				(width 0.1)
				(type default)
			)
			(layer "F.Fab")
		)
		(pad "1" smd circle
			(at -0.40005 0 270)
			(size 0 0)
			(layers "F.Cu" "F.Mask" "F.Paste")
			(net "P5V_AUX")
		)
		(pad "2" smd circle
			(at 0.40005 0 270)
			(size 0 0)
			(layers "F.Cu" "F.Mask" "F.Paste")
			(net "P12V_SSD8_PG_G2")
		)
	)
)
